(kicad_pcb
	(version 20221018)
	(generator pcbnew)
	(general
    (thickness 1.562)
  )
	(paper "A4")
	(title_block
    (title "Thunderbolt PCIe Adaper")
    (date "2024-07-09")
    (rev "1.0.3")
    (comment 1 "www.antmicro.com")
    (comment 2 "Antmicro Ltd.")
		(comment 9 "footprints 11-17 of 271")
	)
	(layers
    (0 "F.Cu" signal)
    (1 "In1.Cu" signal)
    (2 "In2.Cu" signal)
    (3 "In3.Cu" signal)
    (4 "In4.Cu" signal)
    (31 "B.Cu" signal)
    (32 "B.Adhes" user "B.Adhesive")
    (33 "F.Adhes" user "F.Adhesive")
    (34 "B.Paste" user)
    (35 "F.Paste" user)
    (36 "B.SilkS" user "B.Silkscreen")
    (37 "F.SilkS" user "F.Silkscreen")
    (38 "B.Mask" user)
    (39 "F.Mask" user)
    (40 "Dwgs.User" user "User.Drawings")
    (41 "Cmts.User" user "User.Comments")
    (42 "Eco1.User" user "User.Eco1")
    (43 "Eco2.User" user "User.Eco2")
    (44 "Edge.Cuts" user)
    (45 "Margin" user)
    (46 "B.CrtYd" user "B.Courtyard")
    (47 "F.CrtYd" user "F.Courtyard")
    (48 "B.Fab" user)
    (49 "F.Fab" user)
  )
	(footprint "antmicro-footprints:Fiducial_1mm_Mask3mm" (layer "F.Cu")
    (at 161 98)
    (descr "Circular Fiducial, 1.5mm bare copper, 3mm soldermask opening")
    (tags "fiducial")
    (property "Author" "Antmicro")
    (property "License" "Apache-2.0")
    (property "Sheetfile" "thunderbolt-pcie-adapter.kicad_sch")
    (property "Sheetname" "")
    (property "exclude_from_bom" "")
    (property "ki_description" "Fiducial mask")
    (attr through_hole exclude_from_bom)
    (fp_text reference "FID4" (at -1.107 -1.734) (layer "F.SilkS")
        (effects (font (size 0.7 0.7) (thickness 0.15)) (justify left bottom))
    )
    (fp_text value "Fiducial_1mm_Mask3mm" (at 0 2.603) (layer "F.Fab")
        (effects (font (size 0.7 0.7) (thickness 0.15)) (justify left bottom))
    )
    (fp_text user "License: Apache-2.0" (at -1.25 7.003) (layer "F.Fab") hide
        (effects (font (size 0.7 0.7) (thickness 0.15)) (justify left bottom))
    )
    (fp_text user "${REFERENCE}" (at -1.25 4.603) (layer "F.Fab") hide
        (effects (font (size 0.7 0.7) (thickness 0.15)) (justify left bottom))
    )
    (fp_text user "Author: Antmicro" (at -1.25 5.803) (layer "F.Fab") hide
        (effects (font (size 0.7 0.7) (thickness 0.15)) (justify left bottom))
    )
    (fp_circle (center 0 0) (end 1.5 0)
      (stroke (width 0.05) (type solid)) (fill none) (layer "F.CrtYd"))
    (fp_circle (center 0 0) (end 1.5 0)
      (stroke (width 0.15) (type solid)) (fill none) (layer "F.Fab"))
    (pad "" smd circle (at 0 0) (size 1 1) (layers "F.Cu" "F.Mask")
      (solder_mask_margin 1) (clearance 1))
  )
	(footprint "antmicro-footprints:C_0603_1608Metric" (layer "F.Cu")
    (at 114.135001 79.9 -90)
    (descr "Capacitor SMD 0603")
    (tags "capacitor 0603")
    (property "Author" "Antmicro")
    (property "Dielectric" "")
    (property "License" "Apache-2.0")
    (property "MPN" "CL10A226MO7JZNC")
    (property "Manufacturer" "Samsung Electro-Mechanics")
    (property "Sheetfile" "power.kicad_sch")
    (property "Sheetname" "Power")
    (property "Val" "22u")
    (property "Voltage" "16V")
    (property "ki_description" "SMD Multilayer Ceramic Capacitor")
    (property "ki_keywords" "0603, SMT, CAPACITOR, PASSIVE, CERAMIC")
    (attr smd)
    (fp_text reference "C38" (at 1.126 0.597001 -90) (layer "F.SilkS")
        (effects (font (size 0.7 0.7) (thickness 0.15)) (justify left bottom))
    )
    (fp_text value "C_22u_16V_0603" (at -1.42757 1.770288 -90) (layer "F.Fab")
        (effects (font (size 0.7 0.7) (thickness 0.15)) (justify left bottom))
    )
    (fp_text user "${REFERENCE}" (at -1.682 3.895 -90) (layer "F.Fab") hide
        (effects (font (size 0.7 0.7) (thickness 0.15)) (justify left bottom))
    )
    (fp_text user "License: Apache-2.0" (at -1.682 5.895 -90) (layer "F.Fab") hide
        (effects (font (size 0.7 0.7) (thickness 0.15)) (justify left bottom))
    )
    (fp_text user "Author: Antmicro" (at -1.682 4.894 -90) (layer "F.Fab") hide
        (effects (font (size 0.7 0.7) (thickness 0.15)) (justify left bottom))
    )
    (fp_line (start -0.15 -0.4) (end 0.15 -0.4)
      (stroke (width 0.15) (type solid)) (layer "F.SilkS"))
    (fp_line (start -0.15 0.4) (end 0.15 0.4)
      (stroke (width 0.15) (type solid)) (layer "F.SilkS"))
    (fp_rect (start -1.25 -0.65) (end 1.25 0.65)
      (stroke (width 0.05) (type solid)) (fill none) (layer "F.CrtYd"))
    (fp_rect (start -0.8 -0.4) (end 0.8 0.4)
      (stroke (width 0.15) (type solid)) (fill none) (layer "F.Fab"))
    (pad "1" smd roundrect (at -0.7 0 270) (size 0.8 1) (layers "F.Cu" "F.Paste" "F.Mask") (roundrect_rratio 0.2)
      (net 1 "GND") (pintype "passive"))
    (pad "2" smd roundrect (at 0.7 0 270) (size 0.8 1) (layers "F.Cu" "F.Paste" "F.Mask") (roundrect_rratio 0.2)
      (net 75 "Net-(C32-Pad2)") (pintype "passive"))
  )
	(footprint "antmicro-footprints:FB_0805_2012Metric" (layer "F.Cu")
    (at 103.06 74.06 -90)
    (descr "FERRITE BEAD 0805")
    (tags "FERRITE BEAD 0805")
    (property "Author" "Antmicro")
    (property "Current" "")
    (property "License" "Apache-2.0")
    (property "MPN" "BLM21SN300SZ1D")
    (property "Manufacturer" "Murata")
    (property "Sheetfile" "power.kicad_sch")
    (property "Sheetname" "Power")
    (property "Val" "30Z/8.5A")
    (property "ki_description" "Ferrite Bead, 0805 [2012 Metric], 30 ohm, 8.5 A, BLM21SN, 0.004 ohm, ± 10ohm, DC power line")
    (property "ki_keywords" "0805, SMT, FERRITE BEAD, PASSIVE")
    (attr smd)
    (fp_text reference "FB1" (at 0.997 1.079 -90) (layer "F.SilkS")
        (effects (font (size 0.7 0.7) (thickness 0.15)) (justify left bottom))
    )
    (fp_text value "FB_30Z_8.5A_Murata-BLM21SN_0805" (at 0.001 1.801 -90) (layer "F.Fab")
        (effects (font (size 0.7 0.7) (thickness 0.15)) (justify left bottom))
    )
    (fp_text user "${REFERENCE}" (at -1.44 3.801 -90) (layer "F.Fab") hide
        (effects (font (size 0.7 0.7) (thickness 0.15)) (justify left bottom))
    )
    (fp_text user "License: Apache-2.0" (at -1.44 6.201 -90) (layer "F.Fab") hide
        (effects (font (size 0.7 0.7) (thickness 0.15)) (justify left bottom))
    )
    (fp_text user "Author: Antmicro" (at -1.44 5.001 -90) (layer "F.Fab") hide
        (effects (font (size 0.7 0.7) (thickness 0.15)) (justify left bottom))
    )
    (fp_line (start -0.319 0.698) (end 0.281 0.698)
      (stroke (width 0.15) (type solid)) (layer "F.SilkS"))
    (fp_line (start -0.299 -0.698) (end 0.299 -0.698)
      (stroke (width 0.15) (type solid)) (layer "F.SilkS"))
    (fp_rect (start 1.95 -0.9) (end -1.95 0.9)
      (stroke (width 0.05) (type default)) (fill none) (layer "F.CrtYd"))
    (fp_line (start -0.948 -0.681) (end 0.948 -0.681)
      (stroke (width 0.15) (type solid)) (layer "F.Fab"))
    (fp_line (start -0.948 -0.676) (end -0.948 0.676)
      (stroke (width 0.15) (type solid)) (layer "F.Fab"))
    (fp_line (start -0.948 0.681) (end 0.948 0.681)
      (stroke (width 0.15) (type solid)) (layer "F.Fab"))
    (fp_line (start 0.948 -0.676) (end 0.948 0.676)
      (stroke (width 0.15) (type solid)) (layer "F.Fab"))
    (pad "1" smd roundrect (at -1.1 0 270) (size 1.2 1.3) (layers "F.Cu" "F.Paste" "F.Mask") (roundrect_rratio 0.25)
      (net 3 "5V0_USB") (pintype "passive"))
    (pad "2" smd roundrect (at 1.1 0 270) (size 1.2 1.3) (layers "F.Cu" "F.Paste" "F.Mask") (roundrect_rratio 0.25)
      (net 74 "Net-(C10-Pad2)") (pintype "passive"))
  )
	(footprint "antmicro-footprints:SOT-363" (layer "F.Cu")
    (at 118.9475 91.269999 -90)
    (property "Author" "Antmicro")
    (property "License" "Apache-2.0")
    (property "MPN" "DZDH0401DW")
    (property "Manufacturer" "Diodes Incorporated")
    (property "Sheetfile" "power.kicad_sch")
    (property "Sheetname" "Power")
    (property "ki_description" "OR Controller N+1 ORing Controller P-Channel 1:1 SOT-363")
    (property "ki_keywords" "SMT, CONTROLLER, SEMICONDUCTOR, DIODE, PMOS")
    (attr smd)
    (fp_text reference "Q4" (at 0.805001 -2.3375 -90) (layer "F.SilkS")
        (effects (font (size 0.7 0.7) (thickness 0.15)) (justify left bottom))
    )
    (fp_text value "DZDH0401DW" (at 0 2.2 -90) (layer "F.Fab")
        (effects (font (size 0.7 0.7) (thickness 0.15)) (justify left bottom))
    )
    (fp_text user "License: Apache-2.0" (at -1.3 5.2 -90) (layer "F.Fab") hide
        (effects (font (size 0.7 0.7) (thickness 0.15)) (justify left bottom))
    )
    (fp_text user "Author: Antmicro" (at -1.3 6.4 -90) (layer "F.Fab") hide
        (effects (font (size 0.7 0.7) (thickness 0.15)) (justify left bottom))
    )
    (fp_text user "${REFERENCE}" (at -1.3 4 -90) (layer "F.Fab") hide
        (effects (font (size 0.7 0.7) (thickness 0.15)) (justify left bottom))
    )
    (fp_line (start -0.8 1.146) (end -0.8 1.223)
      (stroke (width 0.15) (type solid)) (layer "F.SilkS"))
    (fp_line (start -0.8 1.223) (end 0.803 1.223)
      (stroke (width 0.15) (type solid)) (layer "F.SilkS"))
    (fp_line (start -0.72 -1.153) (end -0.72 -1.228)
      (stroke (width 0.15) (type solid)) (layer "F.SilkS"))
    (fp_line (start 0.803 -1.228) (end -0.72 -1.228)
      (stroke (width 0.15) (type solid)) (layer "F.SilkS"))
    (fp_line (start 0.803 -1.153) (end 0.803 -1.228)
      (stroke (width 0.15) (type solid)) (layer "F.SilkS"))
    (fp_line (start 0.803 1.146) (end 0.803 1.223)
      (stroke (width 0.15) (type solid)) (layer "F.SilkS"))
    (fp_circle (center -0.978102 -1.2) (end -0.928102 -1.2)
      (stroke (width 0.15) (type solid)) (fill solid) (layer "F.SilkS"))
    (fp_rect (start 1.3 -1.3) (end -1.3 1.3)
      (stroke (width 0.05) (type solid)) (fill none) (layer "F.CrtYd"))
    (fp_line (start -0.1 -1.1) (end -0.68 -0.52)
      (stroke (width 0.15) (type solid)) (layer "F.Fab"))
    (fp_rect (start 0.68 1.1) (end -0.68 -1.1)
      (stroke (width 0.15) (type solid)) (fill none) (layer "F.Fab"))
    (pad "1" smd custom (at -0.948 -0.752 180) (size 0.6 0.6) (layers "F.Cu" "F.Paste" "F.Mask")
      (options (clearance outline) (anchor rect))
      (primitives
      ))
    (pad "2" smd rect (at -0.948 -0.002 180) (size 0.4 0.6) (layers "F.Cu" "F.Paste" "F.Mask")
      (net 144 "Net-(Q4-REF)") (pinfunction "REF") (pintype "input"))
    (pad "3" smd custom (at -0.948 0.745 180) (size 0.6 0.6) (layers "F.Cu" "F.Paste" "F.Mask")
      (net 145 "Net-(Q4-BIAS)") (pinfunction "BIAS") (pintype "output")
      (options (clearance outline) (anchor rect))
      (primitives
      ))
    (pad "4" smd custom (at 0.951 0.745 180) (size 0.6 0.6) (layers "F.Cu" "F.Paste" "F.Mask")
      (net 146 "Net-(Q4-S)") (pinfunction "S") (pintype "power_in")
      (options (clearance outline) (anchor rect))
      (primitives
      ))
    (pad "5" smd rect (at 0.951 -0.002 180) (size 0.4 0.6) (layers "F.Cu" "F.Paste" "F.Mask"))
    (pad "6" smd custom (at 0.951 -0.752 180) (size 0.6 0.6) (layers "F.Cu" "F.Paste" "F.Mask")
      (net 60 "12V0_DCDC") (pinfunction "D") (pintype "power_in")
      (options (clearance outline) (anchor rect))
      (primitives
      ))
  )
	(footprint "antmicro-footprints:LED_0603_1608Metric_G" (layer "F.Cu")
    (at 118.9475 89.169999)
    (descr "LED SMD 0603 Green")
    (tags "LED SMD 0603 Green")
    (property "Author" "Antmicro")
    (property "Color" "Green")
    (property "License" "Apache-2.0")
    (property "MPN" "KP-1608CGCK")
    (property "Manufacturer" "Kingbright")
    (property "Sheetfile" "power.kicad_sch")
    (property "Sheetname" "Power")
    (property "ki_description" "LED, Green, SMD, 0603, 20 mA, 2.1 V, 570 nm")
    (property "ki_keywords" "SMT, DIODE, SEMICONDUCTOR, LED")
    (attr smd)
    (fp_text reference "D3" (at 1.1945 0.492001) (layer "F.SilkS")
        (effects (font (size 0.7 0.7) (thickness 0.15)) (justify left bottom))
    )
    (fp_text value "LED_G_0603_KP-1608CGCK" (at -0.001 1.599) (layer "F.Fab")
        (effects (font (size 0.7 0.7) (thickness 0.15)) (justify left bottom))
    )
    (fp_text user "License: Apache-2.0" (at -1.4224 3.599) (layer "F.Fab") hide
        (effects (font (size 0.7 0.7) (thickness 0.15)) (justify left bottom))
    )
    (fp_text user "${REFERENCE}" (at -1.4224 5.999) (layer "F.Fab") hide
        (effects (font (size 0.7 0.7) (thickness 0.15)) (justify left bottom))
    )
    (fp_text user "Author: Antmicro" (at -1.4224 4.799) (layer "F.Fab") hide
        (effects (font (size 0.7 0.7) (thickness 0.15)) (justify left bottom))
    )
    (fp_line (start -1.18 -0.319) (end -1.18 0.321)
      (stroke (width 0.15) (type solid)) (layer "F.SilkS"))
    (fp_line (start -0.094672 0.001008) (end -0.24 0.001008)
      (stroke (width 0.1) (type solid)) (layer "F.SilkS"))
    (fp_line (start -0.094672 0.001008) (end 0.105328 -0.198992)
      (stroke (width 0.1) (type solid)) (layer "F.SilkS"))
    (fp_line (start -0.094672 0.201008) (end -0.094672 -0.198992)
      (stroke (width 0.1) (type solid)) (layer "F.SilkS"))
    (fp_line (start 0.105328 0.001008) (end 0.24 0.001)
      (stroke (width 0.1) (type solid)) (layer "F.SilkS"))
    (fp_line (start 0.105328 0.201008) (end -0.094672 0.001008)
      (stroke (width 0.1) (type solid)) (layer "F.SilkS"))
    (fp_line (start 0.105328 0.201008) (end 0.105328 -0.198992)
      (stroke (width 0.1) (type solid)) (layer "F.SilkS"))
    (fp_line (start 0.22 -0.35) (end -0.22 -0.35)
      (stroke (width 0.15) (type solid)) (layer "F.SilkS"))
    (fp_line (start 0.22 0.35) (end -0.22 0.35)
      (stroke (width 0.15) (type solid)) (layer "F.SilkS"))
    (fp_rect (start 1.25 0.65) (end -1.25 -0.65)
      (stroke (width 0.05) (type solid)) (fill none) (layer "F.CrtYd"))
    (fp_line (start -0.199 -0.202) (end -0.199 0.1)
      (stroke (width 0.15) (type solid)) (layer "F.Fab"))
    (fp_line (start -0.199 0) (end -0.597 0)
      (stroke (width 0.15) (type solid)) (layer "F.Fab"))
    (fp_line (start -0.199 0.2) (end -0.199 0.1)
      (stroke (width 0.15) (type solid)) (layer "F.Fab"))
    (fp_line (start -0.101 0) (end 0.201 0.2)
      (stroke (width 0.15) (type solid)) (layer "F.Fab"))
    (fp_line (start 0.201 -0.202) (end -0.101 0)
      (stroke (width 0.15) (type solid)) (layer "F.Fab"))
    (fp_line (start 0.201 0) (end 0.201 -0.202)
      (stroke (width 0.15) (type solid)) (layer "F.Fab"))
    (fp_line (start 0.201 0.2) (end 0.201 0)
      (stroke (width 0.15) (type solid)) (layer "F.Fab"))
    (fp_line (start 0.599 0) (end 0.201 0)
      (stroke (width 0.15) (type solid)) (layer "F.Fab"))
    (fp_rect (start 0.848 0.4) (end -0.85 -0.402)
      (stroke (width 0.15) (type solid)) (fill none) (layer "F.Fab"))
    (pad "1" smd roundrect (at -0.7 0 180) (size 0.8 1) (layers "F.Cu" "F.Paste" "F.Mask") (roundrect_rratio 0.2)
      (net 121 "Net-(D3-C)") (pinfunction "C") (pintype "passive"))
    (pad "2" smd roundrect (at 0.7 0 180) (size 0.8 1) (layers "F.Cu" "F.Paste" "F.Mask") (roundrect_rratio 0.2)
      (net 60 "12V0_DCDC") (pinfunction "A") (pintype "passive"))
  )
	(footprint "antmicro-footprints:R_0603_1608Metric" (layer "F.Cu")
    (at 163.35 61.97 90)
    (descr "Resistor SMD 0603")
    (tags "resistor SMD 0603")
    (property "Author" "Antmicro")
    (property "Current" "1A")
    (property "License" "Apache-2.0")
    (property "MPN" "CR0603-J/-000ELF")
    (property "Manufacturer" "Bourns")
    (property "Sheetfile" "power.kicad_sch")
    (property "Sheetname" "Power")
    (property "Tolerance" "")
    (property "Val" "0R")
    (property "ki_description" "Zero Ohm Resistor, Jumper, 0603 [1608 Metric], Thick Film, 100 mW, 1 A, Surface Mount Device, CR")
    (property "ki_keywords" "0603, SMT, RESISTOR, PASSIVE")
    (attr smd)
    (fp_text reference "R41" (at -1.022 -0.79 90) (layer "F.SilkS")
        (effects (font (size 0.7 0.7) (thickness 0.15)) (justify left bottom))
    )
    (fp_text value "R_0R_0603" (at 0 1.6 90) (layer "F.Fab")
        (effects (font (size 0.7 0.7) (thickness 0.15)) (justify left bottom))
    )
    (fp_text user "License: Apache-2.0" (at -1.25 5.9 90) (layer "F.Fab") hide
        (effects (font (size 0.7 0.7) (thickness 0.15)) (justify left bottom))
    )
    (fp_text user "Author: Antmicro" (at -1.25 4.9 90) (layer "F.Fab") hide
        (effects (font (size 0.7 0.7) (thickness 0.15)) (justify left bottom))
    )
    (fp_text user "${REFERENCE}" (at -1.25 3.898 90) (layer "F.Fab") hide
        (effects (font (size 0.7 0.7) (thickness 0.15)) (justify left bottom))
    )
    (fp_line (start -0.15 -0.4) (end 0.15 -0.4)
      (stroke (width 0.15) (type solid)) (layer "F.SilkS"))
    (fp_line (start -0.15 0.4) (end 0.15 0.4)
      (stroke (width 0.15) (type solid)) (layer "F.SilkS"))
    (fp_rect (start -1.25 -0.65) (end 1.25 0.65)
      (stroke (width 0.05) (type solid)) (fill none) (layer "F.CrtYd"))
    (fp_rect (start -0.8 -0.4) (end 0.8 0.4)
      (stroke (width 0.15) (type solid)) (fill none) (layer "F.Fab"))
    (pad "1" smd roundrect (at -0.7 0 90) (size 0.8 1) (layers "F.Cu" "F.Paste" "F.Mask") (roundrect_rratio 0.2)
      (net 32 "VBUS") (pintype "passive"))
    (pad "2" smd roundrect (at 0.7 0 90) (size 0.8 1) (layers "F.Cu" "F.Paste" "F.Mask") (roundrect_rratio 0.2)
      (net 3 "5V0_USB") (pintype "passive"))
  )
	(footprint "antmicro-footprints:Resonator_SMD_Abracon_ABM8G_3.2x2.5mm" (layer "F.Cu")
    (at 143.495415 90.001645 -45)
    (property "Author" "Antmicro")
    (property "License" "Apache-2.0")
    (property "MPN" "ABM8G-25.000MHZ-18-D2Y-T3")
    (property "Manufacturer" "Abracon")
    (property "Sheetfile" "tb.kicad_sch")
    (property "Sheetname" "TB Controller")
    (property "Val" "25 MHz")
    (property "ki_description" "Crystal, 25 MHz, SMD, 3.2mm x 2.5mm, 30 ppm, 18 pF, 20 ppm, ABM8G")
    (property "ki_keywords" "SMT, CERAMIC, OSCILLATOR")
    (attr smd)
    (fp_text reference "Y2" (at -2.025903 0.827152 -135) (layer "F.SilkS")
        (effects (font (size 0.7 0.7) (thickness 0.15)) (justify left bottom))
    )
    (fp_text value "Resonator_25MHz_ABM8G" (at -1.75 2.548 -45) (layer "F.Fab")
        (effects (font (size 0.7 0.7) (thickness 0.15)) (justify left bottom))
    )
    (fp_text user "Author: Antmicro" (at -1.75 5 -45) (layer "F.Fab") hide
        (effects (font (size 0.7 0.7) (thickness 0.15)) (justify left bottom))
    )
    (fp_text user "${REFERENCE}" (at -1.75 3.75 -45) (layer "F.Fab") hide
        (effects (font (size 0.7 0.7) (thickness 0.15)) (justify left bottom))
    )
    (fp_text user "License: Apache-2.0" (at -1.75 6.5 -45) (layer "F.Fab") hide
        (effects (font (size 0.7 0.7) (thickness 0.15)) (justify left bottom))
    )
    (fp_line (start -1.6 0.3) (end -1.6 -0.2)
      (stroke (width 0.15) (type solid)) (layer "F.SilkS"))
    (fp_line (start -0.35 -1.25) (end 0.45 -1.25)
      (stroke (width 0.15) (type solid)) (layer "F.SilkS"))
    (fp_line (start -0.35 1.25) (end 0.45 1.25)
      (stroke (width 0.15) (type solid)) (layer "F.SilkS"))
    (fp_line (start 1.6 0.3) (end 1.6 -0.2)
      (stroke (width 0.15) (type solid)) (layer "F.SilkS"))
    (fp_circle (center -1.75 1.5) (end -1.7 1.5)
      (stroke (width 0.15) (type solid)) (fill none) (layer "F.SilkS"))
    (fp_rect (start -1.907 -1.55) (end 2.006 1.649)
      (stroke (width 0.05) (type solid)) (fill none) (layer "F.CrtYd"))
    (pad "1" smd roundrect (at -1.101 0.949 315) (size 1.3 1.1) (layers "F.Cu" "F.Paste" "F.Mask") (roundrect_rratio 0)
      (chamfer_ratio 0.2) (chamfer bottom_left)
      (net 118 "Net-(U4D-XTAL_25_OUT)") (pintype "passive"))
    (pad "2" smd rect (at 1.199 0.949 315) (size 1.3 1.1) (layers "F.Cu" "F.Paste" "F.Mask")
      (net 1 "GND") (pinfunction "SH") (pintype "passive"))
    (pad "3" smd rect (at 1.199 -0.85 315) (size 1.3 1.1) (layers "F.Cu" "F.Paste" "F.Mask")
      (net 117 "Net-(U4D-XTAL_25_IN)") (pintype "passive"))
    (pad "4" smd rect (at -1.101 -0.85 315) (size 1.3 1.1) (layers "F.Cu" "F.Paste" "F.Mask")
      (net 1 "GND") (pinfunction "SH") (pintype "passive"))
  )
)
